# SCM (Grand Teton) — schematic netlist excerpt (pin names and nets, part order shuffled) for the footprints in the layout excerpt that follows; sources: Cadence DE-HDL packaged netlist, KiCad conversion of 12092022_DA0F0TMDCD0_F0T_Management_Board_D_brd_V3_OCP.brd

R569  Q_RES  220 1% CHIP  pkg 0402LF  page 49 : A = HDD_LED_P5V_AUX ; B = P5V_AUX
C159  Q_CAP  0.1UF 25V 10% X7R  pkg 0402  page 28 : A = P3V3_AUX ; B = GND

(kicad_pcb
	(version 20260206)
	(generator "pcbnew")
	(generator_version "10.0")
	(general
		(thickness 1.6)
		(legacy_teardrops no)
	)
	(paper "A4")
	(title_block
		(title "12092022_DA0F0TMDCD0_F0T_Management_Board_D_brd_V3_OCP.brd")
		(comment 1 "Grand Teton / footprints 1407-1408 of 1440")
	)
	(layers
		(0 "F.Cu" signal "TOP")
		(4 "In1.Cu" signal "GND")
		(6 "In2.Cu" signal "IN1")
		(8 "In3.Cu" signal "GND1")
		(10 "In4.Cu" signal "IN2")
		(12 "In5.Cu" signal "VCC")
		(14 "In6.Cu" signal "VCC1")
		(16 "In7.Cu" signal "IN3")
		(18 "In8.Cu" signal "GND2")
		(20 "In9.Cu" signal "IN4")
		(22 "In10.Cu" signal "GND3")
		(2 "B.Cu" signal "BOTTOM")
		(9 "F.Adhes" user "F.Adhesive")
		(11 "B.Adhes" user "B.Adhesive")
		(13 "F.Paste" user "Package Geometry/Pastemask Top")
		(15 "B.Paste" user "Package Geometry/Pastemask Bottom")
		(5 "F.SilkS" user "Ref Des/Silkscreen Top")
		(7 "B.SilkS" user "Ref Des/Silkscreen Bottom")
		(1 "F.Mask" user "Board Geometry/Soldermask Top")
		(3 "B.Mask" user "Board Geometry/Soldermask Bottom")
		(17 "Dwgs.User" user "User.Drawings")
		(19 "Cmts.User" user "User.Comments")
		(21 "Eco1.User" user "User.Eco1")
		(23 "Eco2.User" user "User.Eco2")
		(25 "Edge.Cuts" user "Board Geometry/Outline")
		(27 "Margin" user)
		(31 "F.CrtYd" user "Package Geometry/Place Bound Top")
		(29 "B.CrtYd" user "Package Geometry/Place Bound Bottom")
		(35 "F.Fab" user "Ref Des/Assembly Top")
		(33 "B.Fab" user "Ref Des/Assembly Bottom")
	)
	(footprint ""
		(layer "B.Cu")
		(at 18.8722 -70.1294 -90)
		(property "Reference" "C159"
			(at 0 0 90)
			(layer "B.SilkS")
			(hide yes)
			(effects
				(font
					(size 1.27 1.27)
				)
				(justify mirror)
			)
		)
		(property "Value" ""
			(at 0 0 90)
			(layer "B.Fab")
			(effects
				(font
					(size 1.27 1.27)
				)
				(justify mirror)
			)
		)
		(duplicate_pad_numbers_are_jumpers no)
		(fp_line
			(start -0.7874 0.4064)
			(end 0.7874 0.4064)
			(stroke
				(width 0.1524)
				(type default)
			)
			(layer "B.SilkS")
		)
		(fp_line
			(start 0.7874 0.4064)
			(end 0.7874 -0.4064)
			(stroke
				(width 0.1524)
				(type default)
			)
			(layer "B.SilkS")
		)
		(fp_line
			(start -0.7874 -0.4064)
			(end -0.7874 0.4064)
			(stroke
				(width 0.1524)
				(type default)
			)
			(layer "B.SilkS")
		)
		(fp_line
			(start 0.7874 -0.4064)
			(end -0.7874 -0.4064)
			(stroke
				(width 0.1524)
				(type default)
			)
			(layer "B.SilkS")
		)
		(fp_line
			(start -0.67945 0.3048)
			(end -0.120396 0.3048)
			(stroke
				(width 0.1)
				(type default)
			)
			(layer "B.Fab")
		)
		(fp_line
			(start -0.120396 0.3048)
			(end -0.120396 0.2794)
			(stroke
				(width 0.1)
				(type default)
			)
			(layer "B.Fab")
		)
		(fp_line
			(start 0.12065 0.3048)
			(end 0.67945 0.3048)
			(stroke
				(width 0.1)
				(type default)
			)
			(layer "B.Fab")
		)
		(fp_line
			(start 0.67945 0.3048)
			(end 0.67945 -0.305054)
			(stroke
				(width 0.1)
				(type default)
			)
			(layer "B.Fab")
		)
		(fp_line
			(start -0.120396 0.2794)
			(end 0.12065 0.2794)
			(stroke
				(width 0.1)
				(type default)
			)
			(layer "B.Fab")
		)
		(fp_line
			(start 0.12065 0.2794)
			(end 0.12065 0.3048)
			(stroke
				(width 0.1)
				(type default)
			)
			(layer "B.Fab")
		)
		(fp_line
			(start -0.12065 -0.2794)
			(end -0.12065 -0.3048)
			(stroke
				(width 0.1)
				(type default)
			)
			(layer "B.Fab")
		)
		(fp_line
			(start 0.12065 -0.2794)
			(end -0.12065 -0.2794)
			(stroke
				(width 0.1)
				(type default)
			)
			(layer "B.Fab")
		)
		(fp_line
			(start -0.67945 -0.3048)
			(end -0.67945 0.3048)
			(stroke
				(width 0.1)
				(type default)
			)
			(layer "B.Fab")
		)
		(fp_line
			(start -0.12065 -0.3048)
			(end -0.67945 -0.3048)
			(stroke
				(width 0.1)
				(type default)
			)
			(layer "B.Fab")
		)
		(fp_line
			(start 0.12065 -0.305054)
			(end 0.12065 -0.2794)
			(stroke
				(width 0.1)
				(type default)
			)
			(layer "B.Fab")
		)
		(fp_line
			(start 0.67945 -0.305054)
			(end 0.12065 -0.305054)
			(stroke
				(width 0.1)
				(type default)
			)
			(layer "B.Fab")
		)
		(pad "1" smd circle
			(at 0.40005 0 90)
			(size 0 0)
			(layers "B.Cu" "B.Mask" "B.Paste")
			(net "P3V3_AUX")
		)
		(pad "2" smd circle
			(at -0.40005 0 90)
			(size 0 0)
			(layers "B.Cu" "B.Mask" "B.Paste")
			(net "GND")
		)
	)
	(footprint ""
		(layer "B.Cu")
		(at 21.971 -17.907 90)
		(property "Reference" "R569"
			(at 0 0 90)
			(layer "B.SilkS")
			(hide yes)
			(effects
				(font
					(size 1.27 1.27)
				)
				(justify mirror)
			)
		)
		(property "Value" ""
			(at 0 0 90)
			(layer "B.Fab")
			(effects
				(font
					(size 1.27 1.27)
				)
				(justify mirror)
			)
		)
		(duplicate_pad_numbers_are_jumpers no)
		(fp_line
			(start 0.7874 -0.4064)
			(end -0.7874 -0.4064)
			(stroke
				(width 0.1524)
				(type default)
			)
			(layer "B.SilkS")
		)
		(fp_line
			(start -0.7874 -0.4064)
			(end -0.7874 0.4064)
			(stroke
				(width 0.1524)
				(type default)
			)
			(layer "B.SilkS")
		)
		(fp_line
			(start 0.7874 0.4064)
			(end 0.7874 -0.4064)
			(stroke
				(width 0.1524)
				(type default)
			)
			(layer "B.SilkS")
		)
		(fp_line
			(start -0.7874 0.4064)
			(end 0.7874 0.4064)
			(stroke
				(width 0.1524)
				(type default)
			)
			(layer "B.SilkS")
		)
		(fp_line
			(start 0.67945 -0.305054)
			(end 0.12065 -0.305054)
			(stroke
				(width 0.1)
				(type default)
			)
			(layer "B.Fab")
		)
		(fp_line
			(start 0.12065 -0.305054)
			(end 0.12065 -0.2794)
			(stroke
				(width 0.1)
				(type default)
			)
			(layer "B.Fab")
		)
		(fp_line
			(start -0.12065 -0.3048)
			(end -0.67945 -0.3048)
			(stroke
				(width 0.1)
				(type default)
			)
			(layer "B.Fab")
		)
		(fp_line
			(start -0.67945 -0.3048)
			(end -0.67945 0.3048)
			(stroke
				(width 0.1)
				(type default)
			)
			(layer "B.Fab")
		)
		(fp_line
			(start 0.12065 -0.2794)
			(end -0.12065 -0.2794)
			(stroke
				(width 0.1)
				(type default)
			)
			(layer "B.Fab")
		)
		(fp_line
			(start -0.12065 -0.2794)
			(end -0.12065 -0.3048)
			(stroke
				(width 0.1)
				(type default)
			)
			(layer "B.Fab")
		)
		(fp_line
			(start 0.12065 0.2794)
			(end 0.12065 0.3048)
			(stroke
				(width 0.1)
				(type default)
			)
			(layer "B.Fab")
		)
		(fp_line
			(start -0.120396 0.2794)
			(end 0.12065 0.2794)
			(stroke
				(width 0.1)
				(type default)
			)
			(layer "B.Fab")
		)
		(fp_line
			(start 0.67945 0.3048)
			(end 0.67945 -0.305054)
			(stroke
				(width 0.1)
				(type default)
			)
			(layer "B.Fab")
		)
		(fp_line
			(start 0.12065 0.3048)
			(end 0.67945 0.3048)
			(stroke
				(width 0.1)
				(type default)
			)
			(layer "B.Fab")
		)
		(fp_line
			(start -0.120396 0.3048)
			(end -0.120396 0.2794)
			(stroke
				(width 0.1)
				(type default)
			)
			(layer "B.Fab")
		)
		(fp_line
			(start -0.67945 0.3048)
			(end -0.120396 0.3048)
			(stroke
				(width 0.1)
				(type default)
			)
			(layer "B.Fab")
		)
		(pad "1" smd circle
			(at 0.40005 0 270)
			(size 0 0)
			(layers "B.Cu" "B.Mask" "B.Paste")
			(net "HDD_LED_P5V_AUX")
		)
		(pad "2" smd circle
			(at -0.40005 0 270)
			(size 0 0)
			(layers "B.Cu" "B.Mask" "B.Paste")
			(net "P5V_AUX")
		)
	)
)
